# T6G (Grand Teton) — schematic netlist excerpt (pin names and nets, part order shuffled) for the footprints in the layout excerpt that follows; sources: Cadence DE-HDL packaged netlist, KiCad conversion of 04192023_DAF0TMB3IC0_F0TG_MB_C_brd_V02_OCP.brd

R1681  Q_RES  10 1% CHIP  pkg 0402LF  page 93 : A = I3C_SPD_DDRGL_CPU0_SDA ; B = I3C_SPD_DDRH_CPU0_SDA
C2650  Q_CAP  22UF 4V 20% X6S  pkg C0402  page 70 : A = PVDDIO_P0 ; B = GND
C6687  Q_CAP_DIFFBUS  DIFF BUS_0.22UF 6.3V 20% X6S  pkg C0201  page 330 : \1\ = P5E_CPU1_P1_TX_BUF_C_DP<13> ; \2\ = P5E_CPU1_P1_TX_BUF_DP<13>

(kicad_pcb
	(version 20260206)
	(generator "pcbnew")
	(generator_version "10.0")
	(general
		(thickness 1.6)
		(legacy_teardrops no)
	)
	(paper "A4")
	(title_block
		(title "04192023_DAF0TMB3IC0_F0TG_MB_C_brd_V02_OCP.brd")
		(comment 1 "Grand Teton / footprints 6329-6331 of 8354")
	)
	(layers
		(0 "F.Cu" signal "TOP")
		(4 "In1.Cu" signal "GND")
		(6 "In2.Cu" signal "IN1")
		(8 "In3.Cu" signal "GND1")
		(10 "In4.Cu" signal "IN2")
		(12 "In5.Cu" signal "GND2")
		(14 "In6.Cu" signal "IN3")
		(16 "In7.Cu" signal "GND3")
		(18 "In8.Cu" signal "VCC")
		(20 "In9.Cu" signal "VCC1")
		(22 "In10.Cu" signal "GND4")
		(24 "In11.Cu" signal "IN4")
		(26 "In12.Cu" signal "GND5")
		(28 "In13.Cu" signal "IN5")
		(30 "In14.Cu" signal "GND6")
		(32 "In15.Cu" signal "IN6")
		(34 "In16.Cu" signal "GND7")
		(2 "B.Cu" signal "BOTTOM")
		(9 "F.Adhes" user "F.Adhesive")
		(11 "B.Adhes" user "B.Adhesive")
		(13 "F.Paste" user "Package Geometry/Pastemask Top")
		(15 "B.Paste" user "Package Geometry/Pastemask Bottom")
		(5 "F.SilkS" user "Ref Des/Silkscreen Top")
		(7 "B.SilkS" user "Ref Des/Silkscreen Bottom")
		(1 "F.Mask" user "Board Geometry/Soldermask Top")
		(3 "B.Mask" user "Board Geometry/Soldermask Bottom")
		(17 "Dwgs.User" user "User.Drawings")
		(19 "Cmts.User" user "User.Comments")
		(21 "Eco1.User" user "User.Eco1")
		(23 "Eco2.User" user "User.Eco2")
		(25 "Edge.Cuts" user "Board Geometry/Outline")
		(27 "Margin" user)
		(31 "F.CrtYd" user "Package Geometry/Place Bound Top")
		(29 "B.CrtYd" user "Package Geometry/Place Bound Bottom")
		(35 "F.Fab" user "Ref Des/Assembly Top")
		(33 "B.Fab" user "Ref Des/Assembly Bottom")
	)
	(footprint ""
		(layer "B.Cu")
		(at 423.256456 -195.85051 180)
		(property "Reference" "R1681"
			(at 0 0 0)
			(layer "B.SilkS")
			(hide yes)
			(effects
				(font
					(size 1.27 1.27)
				)
				(justify mirror)
			)
		)
		(property "Value" ""
			(at 0 0 0)
			(layer "B.Fab")
			(effects
				(font
					(size 1.27 1.27)
				)
				(justify mirror)
			)
		)
		(duplicate_pad_numbers_are_jumpers no)
		(fp_line
			(start 0.7874 0.4064)
			(end 0.7874 -0.4064)
			(stroke
				(width 0.1524)
				(type default)
			)
			(layer "B.SilkS")
		)
		(fp_line
			(start 0.7874 -0.4064)
			(end -0.7874 -0.4064)
			(stroke
				(width 0.1524)
				(type default)
			)
			(layer "B.SilkS")
		)
		(fp_line
			(start -0.7874 0.4064)
			(end 0.7874 0.4064)
			(stroke
				(width 0.1524)
				(type default)
			)
			(layer "B.SilkS")
		)
		(fp_line
			(start -0.7874 -0.4064)
			(end -0.7874 0.4064)
			(stroke
				(width 0.1524)
				(type default)
			)
			(layer "B.SilkS")
		)
		(fp_line
			(start 0.67945 0.3048)
			(end 0.67945 -0.305054)
			(stroke
				(width 0.1)
				(type default)
			)
			(layer "B.Fab")
		)
		(fp_line
			(start 0.67945 -0.305054)
			(end 0.12065 -0.305054)
			(stroke
				(width 0.1)
				(type default)
			)
			(layer "B.Fab")
		)
		(fp_line
			(start 0.12065 0.3048)
			(end 0.67945 0.3048)
			(stroke
				(width 0.1)
				(type default)
			)
			(layer "B.Fab")
		)
		(fp_line
			(start 0.12065 0.2794)
			(end 0.12065 0.3048)
			(stroke
				(width 0.1)
				(type default)
			)
			(layer "B.Fab")
		)
		(fp_line
			(start 0.12065 -0.2794)
			(end -0.12065 -0.2794)
			(stroke
				(width 0.1)
				(type default)
			)
			(layer "B.Fab")
		)
		(fp_line
			(start 0.12065 -0.305054)
			(end 0.12065 -0.2794)
			(stroke
				(width 0.1)
				(type default)
			)
			(layer "B.Fab")
		)
		(fp_line
			(start -0.120396 0.3048)
			(end -0.120396 0.2794)
			(stroke
				(width 0.1)
				(type default)
			)
			(layer "B.Fab")
		)
		(fp_line
			(start -0.120396 0.2794)
			(end 0.12065 0.2794)
			(stroke
				(width 0.1)
				(type default)
			)
			(layer "B.Fab")
		)
		(fp_line
			(start -0.12065 -0.2794)
			(end -0.12065 -0.3048)
			(stroke
				(width 0.1)
				(type default)
			)
			(layer "B.Fab")
		)
		(fp_line
			(start -0.12065 -0.3048)
			(end -0.67945 -0.3048)
			(stroke
				(width 0.1)
				(type default)
			)
			(layer "B.Fab")
		)
		(fp_line
			(start -0.67945 0.3048)
			(end -0.120396 0.3048)
			(stroke
				(width 0.1)
				(type default)
			)
			(layer "B.Fab")
		)
		(fp_line
			(start -0.67945 -0.3048)
			(end -0.67945 0.3048)
			(stroke
				(width 0.1)
				(type default)
			)
			(layer "B.Fab")
		)
		(pad "1" smd circle
			(at 0.40005 0)
			(size 0 0)
			(layers "B.Cu" "B.Mask" "B.Paste")
			(net "I3C_SPD_DDRGL_CPU0_SDA")
		)
		(pad "2" smd circle
			(at -0.40005 0)
			(size 0 0)
			(layers "B.Cu" "B.Mask" "B.Paste")
			(net "I3C_SPD_DDRH_CPU0_SDA")
		)
	)
	(footprint ""
		(layer "B.Cu")
		(at 348.151958 -261.870952)
		(property "Reference" "C2650"
			(at 0 0 0)
			(layer "B.SilkS")
			(hide yes)
			(effects
				(font
					(size 1.27 1.27)
				)
				(justify mirror)
			)
		)
		(property "Value" ""
			(at 0 0 0)
			(layer "B.Fab")
			(effects
				(font
					(size 1.27 1.27)
				)
				(justify mirror)
			)
		)
		(duplicate_pad_numbers_are_jumpers no)
		(fp_line
			(start -0.7874 -0.4064)
			(end -0.7874 0.4064)
			(stroke
				(width 0.1524)
				(type default)
			)
			(layer "B.SilkS")
		)
		(fp_line
			(start -0.7874 0.4064)
			(end 0.7874 0.4064)
			(stroke
				(width 0.1524)
				(type default)
			)
			(layer "B.SilkS")
		)
		(fp_line
			(start 0.7874 -0.4064)
			(end -0.7874 -0.4064)
			(stroke
				(width 0.1524)
				(type default)
			)
			(layer "B.SilkS")
		)
		(fp_line
			(start 0.7874 0.4064)
			(end 0.7874 -0.4064)
			(stroke
				(width 0.1524)
				(type default)
			)
			(layer "B.SilkS")
		)
		(fp_line
			(start -0.67945 -0.3048)
			(end -0.67945 0.3048)
			(stroke
				(width 0.1)
				(type default)
			)
			(layer "B.Fab")
		)
		(fp_line
			(start -0.67945 0.3048)
			(end -0.120396 0.3048)
			(stroke
				(width 0.1)
				(type default)
			)
			(layer "B.Fab")
		)
		(fp_line
			(start -0.12065 -0.3048)
			(end -0.67945 -0.3048)
			(stroke
				(width 0.1)
				(type default)
			)
			(layer "B.Fab")
		)
		(fp_line
			(start -0.12065 -0.2794)
			(end -0.12065 -0.3048)
			(stroke
				(width 0.1)
				(type default)
			)
			(layer "B.Fab")
		)
		(fp_line
			(start -0.120396 0.2794)
			(end 0.12065 0.2794)
			(stroke
				(width 0.1)
				(type default)
			)
			(layer "B.Fab")
		)
		(fp_line
			(start -0.120396 0.3048)
			(end -0.120396 0.2794)
			(stroke
				(width 0.1)
				(type default)
			)
			(layer "B.Fab")
		)
		(fp_line
			(start 0.12065 -0.305054)
			(end 0.12065 -0.2794)
			(stroke
				(width 0.1)
				(type default)
			)
			(layer "B.Fab")
		)
		(fp_line
			(start 0.12065 -0.2794)
			(end -0.12065 -0.2794)
			(stroke
				(width 0.1)
				(type default)
			)
			(layer "B.Fab")
		)
		(fp_line
			(start 0.12065 0.2794)
			(end 0.12065 0.3048)
			(stroke
				(width 0.1)
				(type default)
			)
			(layer "B.Fab")
		)
		(fp_line
			(start 0.12065 0.3048)
			(end 0.67945 0.3048)
			(stroke
				(width 0.1)
				(type default)
			)
			(layer "B.Fab")
		)
		(fp_line
			(start 0.67945 -0.305054)
			(end 0.12065 -0.305054)
			(stroke
				(width 0.1)
				(type default)
			)
			(layer "B.Fab")
		)
		(fp_line
			(start 0.67945 0.3048)
			(end 0.67945 -0.305054)
			(stroke
				(width 0.1)
				(type default)
			)
			(layer "B.Fab")
		)
		(pad "1" smd circle
			(at 0.40005 0 180)
			(size 0 0)
			(layers "B.Cu" "B.Mask" "B.Paste")
			(net "PVDDIO_P0")
		)
		(pad "2" smd circle
			(at -0.40005 0 180)
			(size 0 0)
			(layers "B.Cu" "B.Mask" "B.Paste")
			(net "GND")
		)
	)
	(footprint ""
		(layer "B.Cu")
		(at 90.036904 -408.517344 90)
		(property "Reference" "C6687"
			(at 0 0 90)
			(layer "B.SilkS")
			(hide yes)
			(effects
				(font
					(size 1.27 1.27)
				)
				(justify mirror)
			)
		)
		(property "Value" ""
			(at 0 0 90)
			(layer "B.Fab")
			(effects
				(font
					(size 1.27 1.27)
				)
				(justify mirror)
			)
		)
		(duplicate_pad_numbers_are_jumpers no)
		(fp_line
			(start 0.299974 -0.150114)
			(end -0.299974 -0.150114)
			(stroke
				(width 0.1)
				(type default)
			)
			(layer "B.Fab")
		)
		(fp_line
			(start -0.299974 -0.150114)
			(end -0.299974 0.150114)
			(stroke
				(width 0.1)
				(type default)
			)
			(layer "B.Fab")
		)
		(fp_line
			(start 0.299974 0.150114)
			(end 0.299974 -0.150114)
			(stroke
				(width 0.1)
				(type default)
			)
			(layer "B.Fab")
		)
		(fp_line
			(start -0.299974 0.150114)
			(end 0.299974 0.150114)
			(stroke
				(width 0.1)
				(type default)
			)
			(layer "B.Fab")
		)
		(pad "1" smd rect
			(at 0.2667 0 270)
			(size 0.3048 0.381)
			(layers "B.Cu" "B.Mask" "B.Paste")
			(net "P5E_CPU1_P1_TX_BUF_C_DP<13>")
		)
		(pad "2" smd rect
			(at -0.2667 0 270)
			(size 0.3048 0.381)
			(layers "B.Cu" "B.Mask" "B.Paste")
			(net "P5E_CPU1_P1_TX_BUF_DP<13>")
		)
	)
)
